# TIMECARD (Time Appliance Project (Time Card)) — schematic netlist excerpt (pin names and nets, part order shuffled) for the footprints in the layout excerpt that follows; sources: Cadence DE-HDL packaged netlist, KiCad conversion of R4006-B0001-02_R01.brd

U21  ISL80101IRAJZ_DFN10  pkg DFN11_118_P0197_TR057X071  page 30
  VOUT_1  = XP1R8V_FPGA
  VOUT_2  = XP1R8V_FPGA
  \sense/adj\  = XP1R8V_FB
  PG  = XP1R8V_PG_R
  GND  = SG
  SS  = XP1R8V_SS
  ENABLE  = XP1R8V_EN_R
  NC  = NC
  VIN_1  = XP1R8V_VIN
  VIN_2  = XP1R8V_VIN
  THRM_PAD  = SG

(kicad_pcb
	(version 20260206)
	(generator "pcbnew")
	(generator_version "10.0")
	(general
		(thickness 1.6)
		(legacy_teardrops no)
	)
	(paper "A4")
	(title_block
		(title "timecard-production-celestica-r4006 — R4006-B0001-02_R01.brd")
		(comment 1 "Time Appliance Project (Time Card) / footprints 269-269 of 1113")
	)
	(layers
		(0 "F.Cu" signal "TOP")
		(4 "In1.Cu" signal "L02_GND1")
		(6 "In2.Cu" signal "L03_SIG1")
		(8 "In3.Cu" signal "L04_GND2")
		(10 "In4.Cu" signal "L05_VCC1")
		(12 "In5.Cu" signal "L06_VCC2")
		(14 "In6.Cu" signal "L07_GND3")
		(16 "In7.Cu" signal "L08_SIG2")
		(18 "In8.Cu" signal "L09_GND4")
		(2 "B.Cu" signal "BOTTOM")
		(9 "F.Adhes" user "F.Adhesive")
		(11 "B.Adhes" user "B.Adhesive")
		(13 "F.Paste" user "Package Geometry/Pastemask Top")
		(15 "B.Paste" user "Package Geometry/Pastemask Bottom")
		(5 "F.SilkS" user "Ref Des/Silkscreen Top")
		(7 "B.SilkS" user "Ref Des/Silkscreen Bottom")
		(1 "F.Mask" user "Board Geometry/Soldermask Top")
		(3 "B.Mask" user "Board Geometry/Soldermask Bottom")
		(17 "Dwgs.User" user "User.Drawings")
		(19 "Cmts.User" user "User.Comments")
		(21 "Eco1.User" user "User.Eco1")
		(23 "Eco2.User" user "User.Eco2")
		(25 "Edge.Cuts" user "Board Geometry/Outline")
		(27 "Margin" user)
		(31 "F.CrtYd" user "Package Geometry/Place Bound Top")
		(29 "B.CrtYd" user "Package Geometry/Place Bound Bottom")
		(35 "F.Fab" user "Ref Des/Assembly Top")
		(33 "B.Fab" user "Ref Des/Assembly Bottom")
	)
	(footprint ""
		(layer "F.Cu")
		(at 129.7432 -68.7578 180)
		(property "Reference" "U21"
			(at -0.3048 2.70383 0)
			(unlocked yes)
			(layer "F.SilkS")
			(effects
				(font
					(size 0.7874 0.5842)
					(thickness 0.1524)
				)
			)
		)
		(property "Value" ""
			(at 0 0 180)
			(layer "F.Fab")
			(effects
				(font
					(size 1.27 1.27)
				)
			)
		)
		(property "Device Type" "ISL80101IRAJZ_DFN10-G222-10136A"
			(at 0.276606 2.583688 180)
			(unlocked yes)
			(layer "F.Fab")
			(hide yes)
			(effects
				(font
					(size 0.7874 0.5842)
					(thickness 0.1524)
				)
			)
		)
		(property "User Part Number" "PARTNUM*"
			(at 0.276606 3.517646 180)
			(unlocked yes)
			(layer "Cmts.User")
			(hide yes)
			(effects
				(font
					(size 0.7874 0.5842)
					(thickness 0.1524)
				)
			)
		)
		(duplicate_pad_numbers_are_jumpers no)
		(fp_line
			(start 2.290318 1.779016)
			(end -2.290318 1.779016)
			(stroke
				(width 0.1)
				(type default)
			)
			(layer "F.SilkS")
		)
		(fp_line
			(start 2.290318 -1.779016)
			(end 2.290318 1.779016)
			(stroke
				(width 0.1)
				(type default)
			)
			(layer "F.SilkS")
		)
		(fp_line
			(start -2.290318 1.779016)
			(end -2.290318 -1.779016)
			(stroke
				(width 0.1)
				(type default)
			)
			(layer "F.SilkS")
		)
		(fp_line
			(start -2.290318 -1.779016)
			(end 2.290318 -1.779016)
			(stroke
				(width 0.1)
				(type default)
			)
			(layer "F.SilkS")
		)
		(fp_poly
			(pts
				(arc
					(start -3.315462 -1.023112)
					(mid -2.553462 -1.023112)
					(end -3.315462 -1.023112)
				)
			)
			(stroke
				(width 0)
				(type default)
			)
			(fill yes)
			(layer "F.SilkS")
		)
		(fp_poly
			(pts
				(xy -0.7239 -0.1016)
				(arc
					(start -0.7239 -0.6477)
					(mid -0.290295 -0.468095)
					(end -0.4699 -0.9017)
				)
				(xy 0.7239 -0.9017) (xy 0.7239 -0.1016)
			)
			(stroke
				(width 0)
				(type default)
			)
			(fill yes)
			(layer "F.Paste")
		)
		(fp_poly
			(pts
				(arc
					(start 0.2159 0.6477)
					(mid 0.288508 0.8255)
					(end 0.46482 0.9017)
				)
				(xy -0.7239 0.9017) (xy -0.7239 0.1016) (xy 0.7239 0.1016)
				(arc
					(start 0.7239 0.64262)
					(mid 0.647736 0.466272)
					(end 0.4699 0.3937)
				)
				(arc
					(start 0.4699 0.3937)
					(mid 0.290295 0.468095)
					(end 0.2159 0.6477)
				)
			)
			(stroke
				(width 0)
				(type default)
			)
			(fill yes)
			(layer "F.Paste")
		)
		(fp_poly
			(pts
				(xy -2.544318 2.033016) (xy 2.544318 2.033016) (xy 2.544318 -2.033016) (xy -2.544318 -2.033016)
			)
			(stroke
				(width 0)
				(type default)
			)
			(fill no)
			(layer "F.CrtYd")
		)
		(fp_line
			(start 1.525016 1.525016)
			(end -1.525016 1.525016)
			(stroke
				(width 0.1)
				(type default)
			)
			(layer "F.Fab")
		)
		(fp_line
			(start 1.525016 -1.525016)
			(end 1.525016 1.525016)
			(stroke
				(width 0.1)
				(type default)
			)
			(layer "F.Fab")
		)
		(fp_line
			(start -1.525016 1.525016)
			(end -1.525016 -1.525016)
			(stroke
				(width 0.1)
				(type default)
			)
			(layer "F.Fab")
		)
		(fp_line
			(start -1.525016 -1.525016)
			(end 1.525016 -1.525016)
			(stroke
				(width 0.1)
				(type default)
			)
			(layer "F.Fab")
		)
		(fp_poly
			(pts
				(arc
					(start -3.315462 -1.023112)
					(mid -2.553462 -1.023112)
					(end -3.315462 -1.023112)
				)
			)
			(stroke
				(width 0)
				(type default)
			)
			(fill yes)
			(layer "F.Fab")
		)
		(fp_text user "6"
			(at 2.7432 0.98425 0)
			(unlocked yes)
			(layer "F.SilkS")
			(effects
				(font
					(size 0.635 0.4064)
					(thickness 0.1524)
				)
			)
		)
		(fp_text user "10"
			(at 2.71145 -0.9398 90)
			(unlocked yes)
			(layer "F.SilkS")
			(effects
				(font
					(size 0.635 0.4064)
					(thickness 0.1524)
				)
			)
		)
		(fp_text user "5"
			(at -2.8448 0.60325 0)
			(unlocked yes)
			(layer "F.SilkS")
			(effects
				(font
					(size 0.635 0.4064)
					(thickness 0.1524)
				)
			)
		)
		(fp_text user "6"
			(at 2.6162 1.05283 0)
			(unlocked yes)
			(layer "F.Fab")
			(effects
				(font
					(size 0.7874 0.5842)
					(thickness 0.1524)
				)
			)
		)
		(fp_text user "10"
			(at 2.57683 -1.3208 90)
			(unlocked yes)
			(layer "F.Fab")
			(effects
				(font
					(size 0.7874 0.5842)
					(thickness 0.1524)
				)
			)
		)
		(fp_text user "5"
			(at -2.825496 1.29921 0)
			(unlocked yes)
			(layer "F.Fab")
			(effects
				(font
					(size 0.7874 0.5842)
					(thickness 0.1524)
				)
			)
		)
		(pad "1" smd circle
			(at -1.515618 -1.000252)
			(size 0 0)
			(layers "F.Cu" "F.Mask" "F.Paste")
			(net "XP1R8V_FPGA")
		)
		(pad "2" smd rect
			(at -1.515618 -0.500126 180)
			(size 1.0414 0.3048)
			(layers "F.Cu" "F.Mask" "F.Paste")
			(net "XP1R8V_FPGA")
		)
		(pad "3" smd rect
			(at -1.515618 0 180)
			(size 1.0414 0.3048)
			(layers "F.Cu" "F.Mask" "F.Paste")
			(net "XP1R8V_FB")
		)
		(pad "4" smd rect
			(at -1.515618 0.500126 180)
			(size 1.0414 0.3048)
			(layers "F.Cu" "F.Mask" "F.Paste")
			(net "XP1R8V_PG_R")
		)
		(pad "5" smd circle
			(at -1.515618 1.000252 180)
			(size 0 0)
			(layers "F.Cu" "F.Mask" "F.Paste")
			(net "SG")
		)
		(pad "6" smd circle
			(at 1.515618 1.000252 180)
			(size 0 0)
			(layers "F.Cu" "F.Mask" "F.Paste")
			(net "XP1R8V_SS")
		)
		(pad "7" smd rect
			(at 1.515618 0.500126 180)
			(size 1.0414 0.3048)
			(layers "F.Cu" "F.Mask" "F.Paste")
			(net "XP1R8V_EN_R")
		)
		(pad "8" smd rect
			(at 1.515618 0 180)
			(size 1.0414 0.3048)
			(layers "F.Cu" "F.Mask" "F.Paste")
			(net "Net_765")
		)
		(pad "9" smd rect
			(at 1.515618 -0.500126 180)
			(size 1.0414 0.3048)
			(layers "F.Cu" "F.Mask" "F.Paste")
			(net "XP1R8V_VIN")
		)
		(pad "10" smd circle
			(at 1.515618 -1.000252)
			(size 0 0)
			(layers "F.Cu" "F.Mask" "F.Paste")
			(net "XP1R8V_VIN")
		)
		(pad "11" smd rect
			(at 0 0 180)
			(size 1.4478 1.8034)
			(layers "F.Cu" "F.Mask" "F.Paste")
			(net "SG")
		)
	)
)
